# S9S_MB_2U (Grand Teton) — schematic netlist excerpt (pin names and nets, part order shuffled) for the footprints in the layout excerpt that follows; sources: Cadence DE-HDL packaged netlist, KiCad conversion of 03242023_DA0F0TMBIJ0_F0T_Motherboard_J_brd_V01_OCP.brd

PU18  ISL69260IRAZT  ISL69260IRAZ-T IC  pkg QFN40_TH_0-4_5X5XE  page 296
  PWM0  = NC_PVCCD_HV_CPU1_APWM8
  PWM1  = NC_PVCCD_HV_CPU1_APWM7
  PWM2  = NC_PVCCD_HV_CPU1_APWM6
  PWM3  = NC_PVCCD_HV_CPU1_APWM5
  PWM4  = NC_PVCCD_HV_CPU1_APWM4
  PWM5  = NC_PVCCD_HV_CPU1_APWM3
  PWM6  = NC_PVCCD_HV_CPU1_APWM2
  PWM7  = PVCCD_HV_CPU1_APWM1
  PMSDA  = SMB_DIO_PVCCD_HV_CPU1
  PMSCL  = SMB_CLK_PVCCD_HV_CPU1
  \npmalert#\  = NC_PVCCD_HV_CPU1_SMB_ALERT
  PG0  = PWRGD_PVCCD_HV_CPU1_R
  EN0  = PVCCD_HV_CPU1_EN_R
  \nvrhot#\  = IRQ_PVCCD_CPU1_VRHOT_LVC3_R_N
  \npinalert#||npsyscrit#\  = PVCCD_HV_CPU1_PIN_ALT
  PG1  = NC_PVCCD_HV_CPU1_BVR_RDY
  SVCLK  = SVID_CLK_PVCCD_HV_CPU1_R
  SVDATA  = SVID_DIO_PVCCD_HV_CPU1_R
  \nsvalert#\  = SVID_ALERT_PVCCD_HV_CPU1_R
  EN1  = GND
  VSEN0  = SH_PVCCD_HV_CPU1_R
  RGND0  = VSENSE_PVCCD_HV_CPU1_DN
  CS7  = PVCCD_HV_CPU1_ACSP1
  CS6  = NC_PVCCD_HV_CPU1_ACSP2
  CS5  = NC_PVCCD_HV_CPU1_ACSP3
  CS4  = NC_PVCCD_HV_CPU1_ACSP4
  CS3  = NC_PVCCD_HV_CPU1_ACSP5
  CS2  = NC_PVCCD_HV_CPU1_ACSP6
  CS1  = NC_PVCCD_HV_CPU1_ACSP7
  CS0  = NC_PVCCD_HV_CPU1_ACSP8
  RGND1  = GND
  VSEN1  = GND
  CFP  = PVCCD_HV_CPU1_FAULT
  ADDR_CFG  = PVCCD_HV_CPU1_ADDR
  TEMP0  = PVCCD_HV_CPU1_ATSEN
  \temp1||isys\  = PVCCD_HV_CPU1_ISYS_R
  \vmon||iinsen||vsys||isys\  = PVCCD_HV_CPU1_ISENSE_P
  \vinsen||vsys\  = PVCCD_HV_CPU1_ISENSE_N
  VCC  = PVCCD_HV_CPU1_VCC
  VCCS  = PVCCD_HV_CPU1_VREF
  TH_GND  = GND

(kicad_pcb
	(version 20260206)
	(generator "pcbnew")
	(generator_version "10.0")
	(general
		(thickness 1.6)
		(legacy_teardrops no)
	)
	(paper "A4")
	(title_block
		(title "03242023_DA0F0TMBIJ0_F0T_Motherboard_J_brd_V01_OCP.brd")
		(comment 1 "Grand Teton / footprint 245 of 6105 (PU18), pads 1-41 of 41")
	)
	(layers
		(0 "F.Cu" signal "TOP")
		(4 "In1.Cu" signal "GND")
		(6 "In2.Cu" signal "IN1")
		(8 "In3.Cu" signal "GND1")
		(10 "In4.Cu" signal "IN2")
		(12 "In5.Cu" signal "GND2")
		(14 "In6.Cu" signal "IN3")
		(16 "In7.Cu" signal "GND3")
		(18 "In8.Cu" signal "VCC")
		(20 "In9.Cu" signal "VCC1")
		(22 "In10.Cu" signal "GND4")
		(24 "In11.Cu" signal "IN4")
		(26 "In12.Cu" signal "GND5")
		(28 "In13.Cu" signal "IN5")
		(30 "In14.Cu" signal "GND6")
		(32 "In15.Cu" signal "IN6")
		(34 "In16.Cu" signal "GND7")
		(2 "B.Cu" signal "BOTTOM")
		(9 "F.Adhes" user "F.Adhesive")
		(11 "B.Adhes" user "B.Adhesive")
		(13 "F.Paste" user "Package Geometry/Pastemask Top")
		(15 "B.Paste" user "Package Geometry/Pastemask Bottom")
		(5 "F.SilkS" user "Ref Des/Silkscreen Top")
		(7 "B.SilkS" user "Ref Des/Silkscreen Bottom")
		(1 "F.Mask" user "Board Geometry/Soldermask Top")
		(3 "B.Mask" user "Board Geometry/Soldermask Bottom")
		(17 "Dwgs.User" user "User.Drawings")
		(19 "Cmts.User" user "User.Comments")
		(21 "Eco1.User" user "User.Eco1")
		(23 "Eco2.User" user "User.Eco2")
		(25 "Edge.Cuts" user "Board Geometry/Outline")
		(27 "Margin" user)
		(31 "F.CrtYd" user "Package Geometry/Place Bound Top")
		(29 "B.CrtYd" user "Package Geometry/Place Bound Bottom")
		(35 "F.Fab" user "Ref Des/Assembly Top")
		(33 "B.Fab" user "Ref Des/Assembly Bottom")
	)
	(footprint ""
		(layer "F.Cu")
		(at 27.662886 -164.827204 -90)
		(property "Reference" "PU18"
			(at -0.638048 -8.11022 0)
			(unlocked yes)
			(layer "F.SilkS")
			(effects
				(font
					(size 0.7874 0.5842)
					(thickness 0.1524)
				)
			)
		)
		(property "Value" ""
			(at 0 0 270)
			(layer "F.Fab")
			(effects
				(font
					(size 1.27 1.27)
				)
			)
		)
		(duplicate_pad_numbers_are_jumpers no)
		(pad "1" smd rect
			(at -2.400046 -1.800098 180)
			(size 0.1778 0.6096)
			(layers "F.Cu" "F.Mask" "F.Paste")
			(net "NC_PVCCD_HV_CPU1_APWM8")
		)
		(pad "2" smd rect
			(at -2.400046 -1.400048 180)
			(size 0.1778 0.6096)
			(layers "F.Cu" "F.Mask" "F.Paste")
			(net "NC_PVCCD_HV_CPU1_APWM7")
		)
		(pad "3" smd rect
			(at -2.400046 -0.999998 180)
			(size 0.1778 0.6096)
			(layers "F.Cu" "F.Mask" "F.Paste")
			(net "NC_PVCCD_HV_CPU1_APWM6")
		)
		(pad "4" smd rect
			(at -2.400046 -0.599948 180)
			(size 0.1778 0.6096)
			(layers "F.Cu" "F.Mask" "F.Paste")
			(net "NC_PVCCD_HV_CPU1_APWM5")
		)
		(pad "5" smd rect
			(at -2.400046 -0.199898 180)
			(size 0.1778 0.6096)
			(layers "F.Cu" "F.Mask" "F.Paste")
			(net "NC_PVCCD_HV_CPU1_APWM4")
		)
		(pad "6" smd rect
			(at -2.400046 0.199898 180)
			(size 0.1778 0.6096)
			(layers "F.Cu" "F.Mask" "F.Paste")
			(net "NC_PVCCD_HV_CPU1_APWM3")
		)
		(pad "7" smd rect
			(at -2.400046 0.599948 180)
			(size 0.1778 0.6096)
			(layers "F.Cu" "F.Mask" "F.Paste")
			(net "NC_PVCCD_HV_CPU1_APWM2")
		)
		(pad "8" smd rect
			(at -2.400046 0.999998 180)
			(size 0.1778 0.6096)
			(layers "F.Cu" "F.Mask" "F.Paste")
			(net "PVCCD_HV_CPU1_APWM1")
		)
		(pad "9" smd rect
			(at -2.400046 1.400048 180)
			(size 0.1778 0.6096)
			(layers "F.Cu" "F.Mask" "F.Paste")
			(net "SMB_DIO_PVCCD_HV_CPU1")
		)
		(pad "10" smd rect
			(at -2.400046 1.800098 180)
			(size 0.1778 0.6096)
			(layers "F.Cu" "F.Mask" "F.Paste")
			(net "SMB_CLK_PVCCD_HV_CPU1")
		)
		(pad "11" smd rect
			(at -1.800098 2.400046 270)
			(size 0.1778 0.6096)
			(layers "F.Cu" "F.Mask" "F.Paste")
			(net "NC_PVCCD_HV_CPU1_SMB_ALERT")
		)
		(pad "12" smd rect
			(at -1.400048 2.400046 270)
			(size 0.1778 0.6096)
			(layers "F.Cu" "F.Mask" "F.Paste")
			(net "PWRGD_PVCCD_HV_CPU1_R")
		)
		(pad "13" smd rect
			(at -0.999998 2.400046 270)
			(size 0.1778 0.6096)
			(layers "F.Cu" "F.Mask" "F.Paste")
			(net "PVCCD_HV_CPU1_EN_R")
		)
		(pad "14" smd rect
			(at -0.599948 2.400046 270)
			(size 0.1778 0.6096)
			(layers "F.Cu" "F.Mask" "F.Paste")
			(net "IRQ_PVCCD_CPU1_VRHOT_LVC3_R_N")
		)
		(pad "15" smd rect
			(at -0.199898 2.400046 270)
			(size 0.1778 0.6096)
			(layers "F.Cu" "F.Mask" "F.Paste")
			(net "PVCCD_HV_CPU1_PIN_ALT")
		)
		(pad "16" smd rect
			(at 0.199898 2.400046 270)
			(size 0.1778 0.6096)
			(layers "F.Cu" "F.Mask" "F.Paste")
			(net "NC_PVCCD_HV_CPU1_BVR_RDY")
		)
		(pad "17" smd rect
			(at 0.599948 2.400046 270)
			(size 0.1778 0.6096)
			(layers "F.Cu" "F.Mask" "F.Paste")
			(net "SVID_CLK_PVCCD_HV_CPU1_R")
		)
		(pad "18" smd rect
			(at 0.999998 2.400046 270)
			(size 0.1778 0.6096)
			(layers "F.Cu" "F.Mask" "F.Paste")
			(net "SVID_DIO_PVCCD_HV_CPU1_R")
		)
		(pad "19" smd rect
			(at 1.400048 2.400046 270)
			(size 0.1778 0.6096)
			(layers "F.Cu" "F.Mask" "F.Paste")
			(net "SVID_ALERT_PVCCD_HV_CPU1_R")
		)
		(pad "20" smd rect
			(at 1.800098 2.400046 270)
			(size 0.1778 0.6096)
			(layers "F.Cu" "F.Mask" "F.Paste")
			(net "GND")
		)
		(pad "21" smd rect
			(at 2.400046 1.800098 180)
			(size 0.1778 0.6096)
			(layers "F.Cu" "F.Mask" "F.Paste")
			(net "SH_PVCCD_HV_CPU1_R")
		)
		(pad "22" smd rect
			(at 2.400046 1.400048 180)
			(size 0.1778 0.6096)
			(layers "F.Cu" "F.Mask" "F.Paste")
			(net "VSENSE_PVCCD_HV_CPU1_DN")
		)
		(pad "23" smd rect
			(at 2.400046 0.999998 180)
			(size 0.1778 0.6096)
			(layers "F.Cu" "F.Mask" "F.Paste")
			(net "PVCCD_HV_CPU1_ACSP1")
		)
		(pad "24" smd rect
			(at 2.400046 0.599948 180)
			(size 0.1778 0.6096)
			(layers "F.Cu" "F.Mask" "F.Paste")
			(net "NC_PVCCD_HV_CPU1_ACSP2")
		)
		(pad "25" smd rect
			(at 2.400046 0.199898 180)
			(size 0.1778 0.6096)
			(layers "F.Cu" "F.Mask" "F.Paste")
			(net "NC_PVCCD_HV_CPU1_ACSP3")
		)
		(pad "26" smd rect
			(at 2.400046 -0.199898 180)
			(size 0.1778 0.6096)
			(layers "F.Cu" "F.Mask" "F.Paste")
			(net "NC_PVCCD_HV_CPU1_ACSP4")
		)
		(pad "27" smd rect
			(at 2.400046 -0.599948 180)
			(size 0.1778 0.6096)
			(layers "F.Cu" "F.Mask" "F.Paste")
			(net "NC_PVCCD_HV_CPU1_ACSP5")
		)
		(pad "28" smd rect
			(at 2.400046 -0.999998 180)
			(size 0.1778 0.6096)
			(layers "F.Cu" "F.Mask" "F.Paste")
			(net "NC_PVCCD_HV_CPU1_ACSP6")
		)
		(pad "29" smd rect
			(at 2.400046 -1.400048 180)
			(size 0.1778 0.6096)
			(layers "F.Cu" "F.Mask" "F.Paste")
			(net "NC_PVCCD_HV_CPU1_ACSP7")
		)
		(pad "30" smd rect
			(at 2.400046 -1.800098 180)
			(size 0.1778 0.6096)
			(layers "F.Cu" "F.Mask" "F.Paste")
			(net "NC_PVCCD_HV_CPU1_ACSP8")
		)
		(pad "31" smd rect
			(at 1.800098 -2.400046 270)
			(size 0.1778 0.6096)
			(layers "F.Cu" "F.Mask" "F.Paste")
			(net "GND")
		)
		(pad "32" smd rect
			(at 1.400048 -2.400046 270)
			(size 0.1778 0.6096)
			(layers "F.Cu" "F.Mask" "F.Paste")
			(net "GND")
		)
		(pad "33" smd rect
			(at 0.999998 -2.400046 270)
			(size 0.1778 0.6096)
			(layers "F.Cu" "F.Mask" "F.Paste")
			(net "PVCCD_HV_CPU1_FAULT")
		)
		(pad "34" smd rect
			(at 0.599948 -2.400046 270)
			(size 0.1778 0.6096)
			(layers "F.Cu" "F.Mask" "F.Paste")
			(net "PVCCD_HV_CPU1_ADDR")
		)
		(pad "35" smd rect
			(at 0.199898 -2.400046 270)
			(size 0.1778 0.6096)
			(layers "F.Cu" "F.Mask" "F.Paste")
			(net "PVCCD_HV_CPU1_ATSEN")
		)
		(pad "36" smd rect
			(at -0.199898 -2.400046 270)
			(size 0.1778 0.6096)
			(layers "F.Cu" "F.Mask" "F.Paste")
			(net "PVCCD_HV_CPU1_ISYS_R")
		)
		(pad "37" smd rect
			(at -0.599948 -2.400046 270)
			(size 0.1778 0.6096)
			(layers "F.Cu" "F.Mask" "F.Paste")
			(net "PVCCD_HV_CPU1_ISENSE_P")
		)
		(pad "38" smd rect
			(at -0.999998 -2.400046 270)
			(size 0.1778 0.6096)
			(layers "F.Cu" "F.Mask" "F.Paste")
			(net "PVCCD_HV_CPU1_ISENSE_N")
		)
		(pad "39" smd rect
			(at -1.400048 -2.400046 270)
			(size 0.1778 0.6096)
			(layers "F.Cu" "F.Mask" "F.Paste")
			(net "PVCCD_HV_CPU1_VCC")
		)
		(pad "40" smd rect
			(at -1.800098 -2.400046 270)
			(size 0.1778 0.6096)
			(layers "F.Cu" "F.Mask" "F.Paste")
			(net "PVCCD_HV_CPU1_VREF")
		)
		(pad "TH" smd rect
			(at 0 0 270)
			(size 3.6576 3.6576)
			(layers "F.Cu" "F.Mask" "F.Paste")
			(net "GND")
		)
	)
)
